(kicad_pcb
	(version 20260206)
	(generator "pcbnew")
	(generator_version "10.0")
	(general
		(thickness 1.6)
		(legacy_teardrops no)
	)
	(paper "A4")
	(title_block
		(title "04192023_DAF0TMB3IC0_F0TG_MB_C_brd_V02_OCP.brd")
		(comment 1 "Grand Teton / footprints 3027-3033 of 8354")
	)
	(layers
		(0 "F.Cu" signal "TOP")
		(4 "In1.Cu" signal "GND")
		(6 "In2.Cu" signal "IN1")
		(8 "In3.Cu" signal "GND1")
		(10 "In4.Cu" signal "IN2")
		(12 "In5.Cu" signal "GND2")
		(14 "In6.Cu" signal "IN3")
		(16 "In7.Cu" signal "GND3")
		(18 "In8.Cu" signal "VCC")
		(20 "In9.Cu" signal "VCC1")
		(22 "In10.Cu" signal "GND4")
		(24 "In11.Cu" signal "IN4")
		(26 "In12.Cu" signal "GND5")
		(28 "In13.Cu" signal "IN5")
		(30 "In14.Cu" signal "GND6")
		(32 "In15.Cu" signal "IN6")
		(34 "In16.Cu" signal "GND7")
		(2 "B.Cu" signal "BOTTOM")
		(9 "F.Adhes" user "F.Adhesive")
		(11 "B.Adhes" user "B.Adhesive")
		(13 "F.Paste" user "Package Geometry/Pastemask Top")
		(15 "B.Paste" user "Package Geometry/Pastemask Bottom")
		(5 "F.SilkS" user "Ref Des/Silkscreen Top")
		(7 "B.SilkS" user "Ref Des/Silkscreen Bottom")
		(1 "F.Mask" user "Board Geometry/Soldermask Top")
		(3 "B.Mask" user "Board Geometry/Soldermask Bottom")
		(17 "Dwgs.User" user "User.Drawings")
		(19 "Cmts.User" user "User.Comments")
		(21 "Eco1.User" user "User.Eco1")
		(23 "Eco2.User" user "User.Eco2")
		(25 "Edge.Cuts" user "Board Geometry/Outline")
		(27 "Margin" user)
		(31 "F.CrtYd" user "Package Geometry/Place Bound Top")
		(29 "B.CrtYd" user "Package Geometry/Place Bound Bottom")
		(35 "F.Fab" user "Ref Des/Assembly Top")
		(33 "B.Fab" user "Ref Des/Assembly Bottom")
	)
	(footprint ""
		(layer "F.Cu")
		(at 438.488836 -168.716452 180)
		(property "Reference" "U106"
			(at -0.808228 2.125726 0)
			(unlocked yes)
			(layer "F.SilkS")
			(effects
				(font
					(size 0.7874 0.5842)
					(thickness 0.1524)
				)
			)
		)
		(property "Value" ""
			(at 0 0 180)
			(layer "F.Fab")
			(effects
				(font
					(size 1.27 1.27)
				)
			)
		)
		(duplicate_pad_numbers_are_jumpers no)
		(fp_line
			(start 1.03378 1.284478)
			(end -1.03378 1.284478)
			(stroke
				(width 0.1524)
				(type default)
			)
			(layer "F.SilkS")
		)
		(fp_line
			(start 1.03378 -1.284478)
			(end 1.03378 1.284478)
			(stroke
				(width 0.1524)
				(type default)
			)
			(layer "F.SilkS")
		)
		(fp_line
			(start -1.03378 1.284478)
			(end -1.03378 -1.284478)
			(stroke
				(width 0.1524)
				(type default)
			)
			(layer "F.SilkS")
		)
		(fp_line
			(start -1.03378 -1.284478)
			(end 1.03378 -1.284478)
			(stroke
				(width 0.1524)
				(type default)
			)
			(layer "F.SilkS")
		)
		(fp_poly
			(pts
				(xy -1.806702 -1.052576) (xy -1.201674 -0.750062) (xy -1.806702 -0.447548)
			)
			(stroke
				(width 0)
				(type default)
			)
			(fill yes)
			(layer "F.SilkS")
		)
		(fp_line
			(start 0.774954 1.02489)
			(end -0.774954 1.02489)
			(stroke
				(width 0.1)
				(type default)
			)
			(layer "F.Fab")
		)
		(fp_line
			(start 0.774954 -1.02489)
			(end 0.774954 1.02489)
			(stroke
				(width 0.1)
				(type default)
			)
			(layer "F.Fab")
		)
		(fp_line
			(start -0.774954 1.02489)
			(end -0.774954 -1.02489)
			(stroke
				(width 0.1)
				(type default)
			)
			(layer "F.Fab")
		)
		(fp_line
			(start -0.774954 -1.02489)
			(end 0.774954 -1.02489)
			(stroke
				(width 0.1)
				(type default)
			)
			(layer "F.Fab")
		)
		(fp_poly
			(pts
				(xy -1.201674 -0.750062) (xy -1.806702 -0.447548) (xy -1.806702 -1.052576)
			)
			(stroke
				(width 0)
				(type default)
			)
			(fill yes)
			(layer "F.Fab")
		)
		(pad "1" smd rect
			(at -0.64008 -0.750062 270)
			(size 0.3048 0.5334)
			(layers "F.Cu" "F.Mask" "F.Paste")
			(net "I3C_1_SPD_DDRGL_CPU0_SCL")
		)
		(pad "2" smd rect
			(at -0.64008 -0.249936 270)
			(size 0.254 0.5334)
			(layers "F.Cu" "F.Mask" "F.Paste")
			(net "I3C_1_SPD_DDRGL_CPU0_SDA")
		)
		(pad "3" smd rect
			(at -0.64008 0.249936 270)
			(size 0.254 0.5334)
			(layers "F.Cu" "F.Mask" "F.Paste")
			(net "I3C_SCM_1_R_SCL")
		)
		(pad "4" smd rect
			(at -0.64008 0.750062 270)
			(size 0.3048 0.5334)
			(layers "F.Cu" "F.Mask" "F.Paste")
			(net "I3C_SCM_1_R_SDA")
		)
		(pad "5" smd rect
			(at 0 0.839978 180)
			(size 0.3302 0.635)
			(layers "F.Cu" "F.Mask" "F.Paste")
			(net "GND")
		)
		(pad "6" smd rect
			(at 0.64008 0.750062 270)
			(size 0.3048 0.5334)
			(layers "F.Cu" "F.Mask" "F.Paste")
			(net "FM_I3C_CPU0_MUX1_OE_N")
		)
		(pad "7" smd rect
			(at 0.64008 0.249936 270)
			(size 0.254 0.5334)
			(layers "F.Cu" "F.Mask" "F.Paste")
			(net "I3C_SPD_DDRGL_CPU0_LVC1_SDA")
		)
		(pad "8" smd rect
			(at 0.64008 -0.249936 270)
			(size 0.254 0.5334)
			(layers "F.Cu" "F.Mask" "F.Paste")
			(net "I3C_SPD_DDRGL_CPU0_LVC1_SCL")
		)
		(pad "9" smd rect
			(at 0.64008 -0.750062 270)
			(size 0.3048 0.5334)
			(layers "F.Cu" "F.Mask" "F.Paste")
			(net "FM_I3C_CPU0_MUX1_SEL")
		)
		(pad "10" smd rect
			(at 0 -0.839978 180)
			(size 0.3302 0.635)
			(layers "F.Cu" "F.Mask" "F.Paste")
			(net "P3V3_AUX")
		)
	)
	(footprint ""
		(layer "F.Cu")
		(at 177.8762 -96.103948 90)
		(property "Reference" "R239"
			(at 0 0 90)
			(layer "F.SilkS")
			(hide yes)
			(effects
				(font
					(size 1.27 1.27)
				)
			)
		)
		(property "Value" ""
			(at 0 0 90)
			(layer "F.Fab")
			(effects
				(font
					(size 1.27 1.27)
				)
			)
		)
		(duplicate_pad_numbers_are_jumpers no)
		(fp_line
			(start 0.7874 -0.4064)
			(end 0.7874 0.4064)
			(stroke
				(width 0.1524)
				(type default)
			)
			(layer "F.SilkS")
		)
		(fp_line
			(start -0.7874 -0.4064)
			(end 0.7874 -0.4064)
			(stroke
				(width 0.1524)
				(type default)
			)
			(layer "F.SilkS")
		)
		(fp_line
			(start 0.7874 0.4064)
			(end -0.7874 0.4064)
			(stroke
				(width 0.1524)
				(type default)
			)
			(layer "F.SilkS")
		)
		(fp_line
			(start -0.7874 0.4064)
			(end -0.7874 -0.4064)
			(stroke
				(width 0.1524)
				(type default)
			)
			(layer "F.SilkS")
		)
		(fp_line
			(start -0.12065 -0.305054)
			(end -0.12065 -0.2794)
			(stroke
				(width 0.1)
				(type default)
			)
			(layer "F.Fab")
		)
		(fp_line
			(start -0.67945 -0.305054)
			(end -0.12065 -0.305054)
			(stroke
				(width 0.1)
				(type default)
			)
			(layer "F.Fab")
		)
		(fp_line
			(start 0.67945 -0.3048)
			(end 0.67945 0.3048)
			(stroke
				(width 0.1)
				(type default)
			)
			(layer "F.Fab")
		)
		(fp_line
			(start 0.12065 -0.3048)
			(end 0.67945 -0.3048)
			(stroke
				(width 0.1)
				(type default)
			)
			(layer "F.Fab")
		)
		(fp_line
			(start 0.12065 -0.2794)
			(end 0.12065 -0.3048)
			(stroke
				(width 0.1)
				(type default)
			)
			(layer "F.Fab")
		)
		(fp_line
			(start -0.12065 -0.2794)
			(end 0.12065 -0.2794)
			(stroke
				(width 0.1)
				(type default)
			)
			(layer "F.Fab")
		)
		(fp_line
			(start 0.120396 0.2794)
			(end -0.12065 0.2794)
			(stroke
				(width 0.1)
				(type default)
			)
			(layer "F.Fab")
		)
		(fp_line
			(start -0.12065 0.2794)
			(end -0.12065 0.3048)
			(stroke
				(width 0.1)
				(type default)
			)
			(layer "F.Fab")
		)
		(fp_line
			(start 0.67945 0.3048)
			(end 0.120396 0.3048)
			(stroke
				(width 0.1)
				(type default)
			)
			(layer "F.Fab")
		)
		(fp_line
			(start 0.120396 0.3048)
			(end 0.120396 0.2794)
			(stroke
				(width 0.1)
				(type default)
			)
			(layer "F.Fab")
		)
		(fp_line
			(start -0.12065 0.3048)
			(end -0.67945 0.3048)
			(stroke
				(width 0.1)
				(type default)
			)
			(layer "F.Fab")
		)
		(fp_line
			(start -0.67945 0.3048)
			(end -0.67945 -0.305054)
			(stroke
				(width 0.1)
				(type default)
			)
			(layer "F.Fab")
		)
		(pad "1" smd circle
			(at -0.40005 0 90)
			(size 0 0)
			(layers "F.Cu" "F.Mask" "F.Paste")
			(net "CPU0_XTRIG_L7")
		)
		(pad "2" smd circle
			(at 0.40005 0 90)
			(size 0 0)
			(layers "F.Cu" "F.Mask" "F.Paste")
			(net "FM_CPU0_XTRIG_L7")
		)
	)
	(footprint ""
		(layer "F.Cu")
		(at 251.474224 -133.622796)
		(property "Reference" "R1655"
			(at 0 0 0)
			(layer "F.SilkS")
			(hide yes)
			(effects
				(font
					(size 1.27 1.27)
				)
			)
		)
		(property "Value" ""
			(at 0 0 0)
			(layer "F.Fab")
			(effects
				(font
					(size 1.27 1.27)
				)
			)
		)
		(duplicate_pad_numbers_are_jumpers no)
		(fp_line
			(start -0.7874 -0.4064)
			(end 0.7874 -0.4064)
			(stroke
				(width 0.1524)
				(type default)
			)
			(layer "F.SilkS")
		)
		(fp_line
			(start -0.7874 0.4064)
			(end -0.7874 -0.4064)
			(stroke
				(width 0.1524)
				(type default)
			)
			(layer "F.SilkS")
		)
		(fp_line
			(start 0.7874 -0.4064)
			(end 0.7874 0.4064)
			(stroke
				(width 0.1524)
				(type default)
			)
			(layer "F.SilkS")
		)
		(fp_line
			(start 0.7874 0.4064)
			(end -0.7874 0.4064)
			(stroke
				(width 0.1524)
				(type default)
			)
			(layer "F.SilkS")
		)
		(fp_line
			(start -0.67945 -0.305054)
			(end -0.12065 -0.305054)
			(stroke
				(width 0.1)
				(type default)
			)
			(layer "F.Fab")
		)
		(fp_line
			(start -0.67945 0.3048)
			(end -0.67945 -0.305054)
			(stroke
				(width 0.1)
				(type default)
			)
			(layer "F.Fab")
		)
		(fp_line
			(start -0.12065 -0.305054)
			(end -0.12065 -0.2794)
			(stroke
				(width 0.1)
				(type default)
			)
			(layer "F.Fab")
		)
		(fp_line
			(start -0.12065 -0.2794)
			(end 0.12065 -0.2794)
			(stroke
				(width 0.1)
				(type default)
			)
			(layer "F.Fab")
		)
		(fp_line
			(start -0.12065 0.2794)
			(end -0.12065 0.3048)
			(stroke
				(width 0.1)
				(type default)
			)
			(layer "F.Fab")
		)
		(fp_line
			(start -0.12065 0.3048)
			(end -0.67945 0.3048)
			(stroke
				(width 0.1)
				(type default)
			)
			(layer "F.Fab")
		)
		(fp_line
			(start 0.120396 0.2794)
			(end -0.12065 0.2794)
			(stroke
				(width 0.1)
				(type default)
			)
			(layer "F.Fab")
		)
		(fp_line
			(start 0.120396 0.3048)
			(end 0.120396 0.2794)
			(stroke
				(width 0.1)
				(type default)
			)
			(layer "F.Fab")
		)
		(fp_line
			(start 0.12065 -0.3048)
			(end 0.67945 -0.3048)
			(stroke
				(width 0.1)
				(type default)
			)
			(layer "F.Fab")
		)
		(fp_line
			(start 0.12065 -0.2794)
			(end 0.12065 -0.3048)
			(stroke
				(width 0.1)
				(type default)
			)
			(layer "F.Fab")
		)
		(fp_line
			(start 0.67945 -0.3048)
			(end 0.67945 0.3048)
			(stroke
				(width 0.1)
				(type default)
			)
			(layer "F.Fab")
		)
		(fp_line
			(start 0.67945 0.3048)
			(end 0.120396 0.3048)
			(stroke
				(width 0.1)
				(type default)
			)
			(layer "F.Fab")
		)
		(pad "1" smd circle
			(at -0.40005 0)
			(size 0 0)
			(layers "F.Cu" "F.Mask" "F.Paste")
			(net "P3V3_AUX")
		)
		(pad "2" smd circle
			(at 0.40005 0)
			(size 0 0)
			(layers "F.Cu" "F.Mask" "F.Paste")
			(net "SPI_CPU0_LVC3_SCM_CS1_N")
		)
	)
	(footprint ""
		(layer "F.Cu")
		(at 376.174 -427.482 90)
		(property "Reference" "C1070"
			(at 0 0 90)
			(layer "F.SilkS")
			(hide yes)
			(effects
				(font
					(size 1.27 1.27)
				)
			)
		)
		(property "Value" ""
			(at 0 0 90)
			(layer "F.Fab")
			(effects
				(font
					(size 1.27 1.27)
				)
			)
		)
		(duplicate_pad_numbers_are_jumpers no)
		(fp_line
			(start 0.299974 -0.150114)
			(end 0.299974 0.150114)
			(stroke
				(width 0.1)
				(type default)
			)
			(layer "F.Fab")
		)
		(fp_line
			(start -0.299974 -0.150114)
			(end 0.299974 -0.150114)
			(stroke
				(width 0.1)
				(type default)
			)
			(layer "F.Fab")
		)
		(fp_line
			(start 0.299974 0.150114)
			(end -0.299974 0.150114)
			(stroke
				(width 0.1)
				(type default)
			)
			(layer "F.Fab")
		)
		(fp_line
			(start -0.299974 0.150114)
			(end -0.299974 -0.150114)
			(stroke
				(width 0.1)
				(type default)
			)
			(layer "F.Fab")
		)
		(pad "1" smd rect
			(at -0.2667 0 90)
			(size 0.3048 0.381)
			(layers "F.Cu" "F.Mask" "F.Paste")
			(net "P3V3_AUX")
		)
		(pad "2" smd rect
			(at 0.2667 0 90)
			(size 0.3048 0.381)
			(layers "F.Cu" "F.Mask" "F.Paste")
			(net "GND")
		)
	)
	(footprint ""
		(layer "F.Cu")
		(at 395.037056 -72.28205 180)
		(property "Reference" "R1273"
			(at 0 0 180)
			(layer "F.SilkS")
			(hide yes)
			(effects
				(font
					(size 1.27 1.27)
				)
			)
		)
		(property "Value" ""
			(at 0 0 180)
			(layer "F.Fab")
			(effects
				(font
					(size 1.27 1.27)
				)
			)
		)
		(duplicate_pad_numbers_are_jumpers no)
		(fp_line
			(start 0.7874 0.4064)
			(end -0.7874 0.4064)
			(stroke
				(width 0.1524)
				(type default)
			)
			(layer "F.SilkS")
		)
		(fp_line
			(start 0.7874 -0.4064)
			(end 0.7874 0.4064)
			(stroke
				(width 0.1524)
				(type default)
			)
			(layer "F.SilkS")
		)
		(fp_line
			(start -0.7874 0.4064)
			(end -0.7874 -0.4064)
			(stroke
				(width 0.1524)
				(type default)
			)
			(layer "F.SilkS")
		)
		(fp_line
			(start -0.7874 -0.4064)
			(end 0.7874 -0.4064)
			(stroke
				(width 0.1524)
				(type default)
			)
			(layer "F.SilkS")
		)
		(fp_line
			(start 0.67945 0.3048)
			(end 0.120396 0.3048)
			(stroke
				(width 0.1)
				(type default)
			)
			(layer "F.Fab")
		)
		(fp_line
			(start 0.67945 -0.3048)
			(end 0.67945 0.3048)
			(stroke
				(width 0.1)
				(type default)
			)
			(layer "F.Fab")
		)
		(fp_line
			(start 0.12065 -0.2794)
			(end 0.12065 -0.3048)
			(stroke
				(width 0.1)
				(type default)
			)
			(layer "F.Fab")
		)
		(fp_line
			(start 0.12065 -0.3048)
			(end 0.67945 -0.3048)
			(stroke
				(width 0.1)
				(type default)
			)
			(layer "F.Fab")
		)
		(fp_line
			(start 0.120396 0.3048)
			(end 0.120396 0.2794)
			(stroke
				(width 0.1)
				(type default)
			)
			(layer "F.Fab")
		)
		(fp_line
			(start 0.120396 0.2794)
			(end -0.12065 0.2794)
			(stroke
				(width 0.1)
				(type default)
			)
			(layer "F.Fab")
		)
		(fp_line
			(start -0.12065 0.3048)
			(end -0.67945 0.3048)
			(stroke
				(width 0.1)
				(type default)
			)
			(layer "F.Fab")
		)
		(fp_line
			(start -0.12065 0.2794)
			(end -0.12065 0.3048)
			(stroke
				(width 0.1)
				(type default)
			)
			(layer "F.Fab")
		)
		(fp_line
			(start -0.12065 -0.2794)
			(end 0.12065 -0.2794)
			(stroke
				(width 0.1)
				(type default)
			)
			(layer "F.Fab")
		)
		(fp_line
			(start -0.12065 -0.305054)
			(end -0.12065 -0.2794)
			(stroke
				(width 0.1)
				(type default)
			)
			(layer "F.Fab")
		)
		(fp_line
			(start -0.67945 0.3048)
			(end -0.67945 -0.305054)
			(stroke
				(width 0.1)
				(type default)
			)
			(layer "F.Fab")
		)
		(fp_line
			(start -0.67945 -0.305054)
			(end -0.12065 -0.305054)
			(stroke
				(width 0.1)
				(type default)
			)
			(layer "F.Fab")
		)
		(pad "1" smd circle
			(at -0.40005 0 180)
			(size 0 0)
			(layers "F.Cu" "F.Mask" "F.Paste")
			(net "SMB_INA230_6_3V3AUX_SCL_R")
		)
		(pad "2" smd circle
			(at 0.40005 0 180)
			(size 0 0)
			(layers "F.Cu" "F.Mask" "F.Paste")
			(net "SMB_INA230_6_3V3AUX_SCL_R1")
		)
	)
	(footprint ""
		(layer "F.Cu")
		(at 113.105946 -257.74523)
		(property "Reference" "C2450"
			(at 0 0 0)
			(layer "F.SilkS")
			(hide yes)
			(effects
				(font
					(size 1.27 1.27)
				)
			)
		)
		(property "Value" ""
			(at 0 0 0)
			(layer "F.Fab")
			(effects
				(font
					(size 1.27 1.27)
				)
			)
		)
		(duplicate_pad_numbers_are_jumpers no)
		(fp_line
			(start -0.7874 -0.4064)
			(end 0.7874 -0.4064)
			(stroke
				(width 0.1524)
				(type default)
			)
			(layer "F.SilkS")
		)
		(fp_line
			(start -0.7874 0.4064)
			(end -0.7874 -0.4064)
			(stroke
				(width 0.1524)
				(type default)
			)
			(layer "F.SilkS")
		)
		(fp_line
			(start 0.7874 -0.4064)
			(end 0.7874 0.4064)
			(stroke
				(width 0.1524)
				(type default)
			)
			(layer "F.SilkS")
		)
		(fp_line
			(start 0.7874 0.4064)
			(end -0.7874 0.4064)
			(stroke
				(width 0.1524)
				(type default)
			)
			(layer "F.SilkS")
		)
		(fp_line
			(start -0.67945 -0.305054)
			(end -0.12065 -0.305054)
			(stroke
				(width 0.1)
				(type default)
			)
			(layer "F.Fab")
		)
		(fp_line
			(start -0.67945 0.3048)
			(end -0.67945 -0.305054)
			(stroke
				(width 0.1)
				(type default)
			)
			(layer "F.Fab")
		)
		(fp_line
			(start -0.12065 -0.305054)
			(end -0.12065 -0.2794)
			(stroke
				(width 0.1)
				(type default)
			)
			(layer "F.Fab")
		)
		(fp_line
			(start -0.12065 -0.2794)
			(end 0.12065 -0.2794)
			(stroke
				(width 0.1)
				(type default)
			)
			(layer "F.Fab")
		)
		(fp_line
			(start -0.12065 0.2794)
			(end -0.12065 0.3048)
			(stroke
				(width 0.1)
				(type default)
			)
			(layer "F.Fab")
		)
		(fp_line
			(start -0.12065 0.3048)
			(end -0.67945 0.3048)
			(stroke
				(width 0.1)
				(type default)
			)
			(layer "F.Fab")
		)
		(fp_line
			(start 0.120396 0.2794)
			(end -0.12065 0.2794)
			(stroke
				(width 0.1)
				(type default)
			)
			(layer "F.Fab")
		)
		(fp_line
			(start 0.120396 0.3048)
			(end 0.120396 0.2794)
			(stroke
				(width 0.1)
				(type default)
			)
			(layer "F.Fab")
		)
		(fp_line
			(start 0.12065 -0.3048)
			(end 0.67945 -0.3048)
			(stroke
				(width 0.1)
				(type default)
			)
			(layer "F.Fab")
		)
		(fp_line
			(start 0.12065 -0.2794)
			(end 0.12065 -0.3048)
			(stroke
				(width 0.1)
				(type default)
			)
			(layer "F.Fab")
		)
		(fp_line
			(start 0.67945 -0.3048)
			(end 0.67945 0.3048)
			(stroke
				(width 0.1)
				(type default)
			)
			(layer "F.Fab")
		)
		(fp_line
			(start 0.67945 0.3048)
			(end 0.120396 0.3048)
			(stroke
				(width 0.1)
				(type default)
			)
			(layer "F.Fab")
		)
		(pad "1" smd circle
			(at -0.40005 0)
			(size 0 0)
			(layers "F.Cu" "F.Mask" "F.Paste")
			(net "PVDDCR_SOC_P1")
		)
		(pad "2" smd circle
			(at 0.40005 0)
			(size 0 0)
			(layers "F.Cu" "F.Mask" "F.Paste")
			(net "GND")
		)
	)
	(footprint ""
		(layer "F.Cu")
		(at 70.125844 -408.517344 -90)
		(property "Reference" "C6643"
			(at 0 0 270)
			(layer "F.SilkS")
			(hide yes)
			(effects
				(font
					(size 1.27 1.27)
				)
			)
		)
		(property "Value" ""
			(at 0 0 270)
			(layer "F.Fab")
			(effects
				(font
					(size 1.27 1.27)
				)
			)
		)
		(duplicate_pad_numbers_are_jumpers no)
		(fp_line
			(start -0.299974 0.150114)
			(end -0.299974 -0.150114)
			(stroke
				(width 0.1)
				(type default)
			)
			(layer "F.Fab")
		)
		(fp_line
			(start 0.299974 0.150114)
			(end -0.299974 0.150114)
			(stroke
				(width 0.1)
				(type default)
			)
			(layer "F.Fab")
		)
		(fp_line
			(start -0.299974 -0.150114)
			(end 0.299974 -0.150114)
			(stroke
				(width 0.1)
				(type default)
			)
			(layer "F.Fab")
		)
		(fp_line
			(start 0.299974 -0.150114)
			(end 0.299974 0.150114)
			(stroke
				(width 0.1)
				(type default)
			)
			(layer "F.Fab")
		)
		(pad "1" smd rect
			(at -0.2667 0 270)
			(size 0.3048 0.381)
			(layers "F.Cu" "F.Mask" "F.Paste")
			(net "P5E_CPU1_P0_TX_BUF_C_DP<7>")
		)
		(pad "2" smd rect
			(at 0.2667 0 270)
			(size 0.3048 0.381)
			(layers "F.Cu" "F.Mask" "F.Paste")
			(net "P5E_CPU1_P0_TX_BUF_DP<7>")
		)
	)
)
